FILE_TYPE=LIBRARY_PARTS;
primitive '232KR2F-2-GP';
  pin
    '1':
      PIN_NUMBER='(1)';
      PIN_TYPE='ANALOG';
      NO_LOAD_CHECK='Both';
      NO_IO_CHECK='Both';
      NO_ASSERT_CHECK='TRUE';
      NO_DIR_CHECK='TRUE';
      ALLOW_CONNECT='TRUE';
    '2':
      PIN_NUMBER='(2)';
      PIN_TYPE='ANALOG';
      NO_LOAD_CHECK='Both';
      NO_IO_CHECK='Both';
      NO_ASSERT_CHECK='TRUE';
      NO_DIR_CHECK='TRUE';
      ALLOW_CONNECT='TRUE';
  end_pin;
  body
    PART_NAME='232KR2F-2-GP';
    BODY_NAME='232KR2F-2-GP';
    PHYS_DES_PREFIX='R';
    CLASS='DISCRETE';
  end_body;
end_primitive;

END.
